# BASEBOARD_FAB2 (Tioga Pass) — schematic netlist excerpt (pin names and nets, part order shuffled) for the footprints in the layout excerpt that follows; sources: Cadence DE-HDL packaged netlist, KiCad conversion of Wiwynn_Tioga_Pass_MB.brd

R1W14  RES  0.0 5% CHIP  pkg 0402  page 115 : A = USB2_PCH_BMC_P5_DP_R ; B = USB2_PCH_BMC_P5_DP
R1W22  RES  0.0 5% CHIP  pkg 0402  page 101 : A = SMB_HOST_STBY_LVC3_SCL ; B = SMB_HOST_STBY_LVC3_SCL_R4
RT20  1R3F-GP  1%  pkg RCL_GP  page 224 : \1\ = VR_PVDDQ_GHJ_PH1_SW_RC ; \2\ = GND

(kicad_pcb
	(version 20260206)
	(generator "pcbnew")
	(generator_version "10.0")
	(general
		(thickness 1.6)
		(legacy_teardrops no)
	)
	(paper "A4")
	(title_block
		(title "Wiwynn_Tioga_Pass_MB.brd")
		(comment 1 "Tioga Pass / footprints 206-208 of 4770")
	)
	(layers
		(0 "F.Cu" signal "TOP")
		(4 "In1.Cu" signal "L2GND")
		(6 "In2.Cu" signal "L3")
		(8 "In3.Cu" signal "L4GND")
		(10 "In4.Cu" signal "L5")
		(12 "In5.Cu" signal "L6GND")
		(14 "In6.Cu" signal "L7VCC")
		(16 "In7.Cu" signal "L8VCC")
		(18 "In8.Cu" signal "L9GND")
		(20 "In9.Cu" signal "L10")
		(22 "In10.Cu" signal "L11GND")
		(24 "In11.Cu" signal "L12")
		(26 "In12.Cu" signal "L13GND")
		(2 "B.Cu" signal "BOTTOM")
		(9 "F.Adhes" user "F.Adhesive")
		(11 "B.Adhes" user "B.Adhesive")
		(13 "F.Paste" user "Package Geometry/Pastemask Top")
		(15 "B.Paste" user "Package Geometry/Pastemask Bottom")
		(5 "F.SilkS" user "Ref Des/Silkscreen Top")
		(7 "B.SilkS" user "Ref Des/Silkscreen Bottom")
		(1 "F.Mask" user "Board Geometry/Soldermask Top")
		(3 "B.Mask" user "Board Geometry/Soldermask Bottom")
		(17 "Dwgs.User" user "User.Drawings")
		(19 "Cmts.User" user "User.Comments")
		(21 "Eco1.User" user "User.Eco1")
		(23 "Eco2.User" user "User.Eco2")
		(25 "Edge.Cuts" user "Board Geometry/Outline")
		(27 "Margin" user)
		(31 "F.CrtYd" user "Package Geometry/Place Bound Top")
		(29 "B.CrtYd" user "Package Geometry/Place Bound Bottom")
		(35 "F.Fab" user "Ref Des/Assembly Top")
		(33 "B.Fab" user "Ref Des/Assembly Bottom")
	)
	(footprint ""
		(layer "F.Cu")
		(at 6.820916 -5.552948 -90)
		(property "Reference" "RT20"
			(at 0 0 270)
			(layer "F.SilkS")
			(hide yes)
			(effects
				(font
					(size 1.27 1.27)
				)
			)
		)
		(property "Value" "*"
			(at -0.0254 -2.6289 270)
			(unlocked yes)
			(layer "F.Fab")
			(hide yes)
			(effects
				(font
					(size 1.27 1.016)
					(thickness 0.1524)
				)
			)
		)
		(property "Device Type" "1R3F-GP_RCL_GP-1R3F-GP,64.1R00A"
			(at -0.0254 -4.1529 270)
			(unlocked yes)
			(layer "F.Fab")
			(hide yes)
			(effects
				(font
					(size 1.27 1.016)
					(thickness 0.1524)
				)
			)
		)
		(duplicate_pad_numbers_are_jumpers no)
		(fp_line
			(start -0.4826 0)
			(end -0.2032 0)
			(stroke
				(width 0.2032)
				(type default)
			)
			(layer "F.SilkS")
		)
		(fp_line
			(start 0.2032 0)
			(end 0.4826 0)
			(stroke
				(width 0.2032)
				(type default)
			)
			(layer "F.SilkS")
		)
		(fp_rect
			(start -0.5842 1.3335)
			(end 0.5842 -1.3335)
			(stroke
				(width 0)
				(type default)
			)
			(fill no)
			(layer "F.CrtYd")
		)
		(fp_rect
			(start -0.5842 1.3335)
			(end 0.5842 -1.3335)
			(stroke
				(width 0)
				(type default)
			)
			(fill no)
			(layer "F.Fab")
		)
		(pad "1" smd custom
			(at 0 -0.762 270)
			(size 0.2159 0.2159)
			(layers "F.Cu" "F.Mask" "F.Paste")
			(net "VR_PVDDQ_GHJ_PH1_SW_RC")
			(options
				(clearance outline)
				(anchor circle)
			)
			(primitives
				(gr_poly
					(pts
						(arc
							(start -0.3302 -0.4318)
							(mid -0.402042 -0.402042)
							(end -0.4318 -0.3302)
						)
						(arc
							(start -0.4318 0.3302)
							(mid -0.402042 0.402042)
							(end -0.3302 0.4318)
						)
						(arc
							(start 0.3302 0.4318)
							(mid 0.402042 0.402042)
							(end 0.4318 0.3302)
						)
						(arc
							(start 0.4318 -0.3302)
							(mid 0.402042 -0.402042)
							(end 0.3302 -0.4318)
						)
					)
					(width 0)
					(fill yes)
				)
			)
		)
		(pad "2" smd custom
			(at 0 0.762 270)
			(size 0.2159 0.2159)
			(layers "F.Cu" "F.Mask" "F.Paste")
			(net "GND")
			(options
				(clearance outline)
				(anchor circle)
			)
			(primitives
				(gr_poly
					(pts
						(arc
							(start -0.3302 -0.4318)
							(mid -0.402042 -0.402042)
							(end -0.4318 -0.3302)
						)
						(arc
							(start -0.4318 0.3302)
							(mid -0.402042 0.402042)
							(end -0.3302 0.4318)
						)
						(arc
							(start 0.3302 0.4318)
							(mid 0.402042 0.402042)
							(end 0.4318 0.3302)
						)
						(arc
							(start 0.4318 -0.3302)
							(mid 0.402042 -0.402042)
							(end 0.3302 -0.4318)
						)
					)
					(width 0)
					(fill yes)
				)
			)
		)
	)
	(footprint ""
		(layer "F.Cu")
		(at 472.313 -30.607 90)
		(property "Reference" "R1W22"
			(at -0.8382 -0.67818 90)
			(unlocked yes)
			(layer "F.SilkS")
			(effects
				(font
					(size 0.4064 0.254)
					(thickness 0.1524)
				)
				(justify left)
			)
		)
		(property "Value" ""
			(at 0 0 90)
			(layer "F.Fab")
			(effects
				(font
					(size 1.27 1.27)
				)
			)
		)
		(duplicate_pad_numbers_are_jumpers no)
		(fp_poly
			(pts
				(xy -0.2794 -0.1016) (xy 0.2794 -0.1016) (xy 0.2794 0.9906) (xy -0.2794 0.9906)
			)
			(stroke
				(width 0)
				(type default)
			)
			(fill no)
			(layer "F.CrtYd")
		)
		(fp_line
			(start 0.2794 -0.1016)
			(end -0.2794 -0.1016)
			(stroke
				(width 0.1)
				(type default)
			)
			(layer "F.Fab")
		)
		(fp_line
			(start -0.2794 -0.1016)
			(end -0.2794 0.9906)
			(stroke
				(width 0.1)
				(type default)
			)
			(layer "F.Fab")
		)
		(fp_line
			(start 0.2794 0.9906)
			(end 0.2794 -0.1016)
			(stroke
				(width 0.1)
				(type default)
			)
			(layer "F.Fab")
		)
		(fp_line
			(start -0.2794 0.9906)
			(end 0.2794 0.9906)
			(stroke
				(width 0.1)
				(type default)
			)
			(layer "F.Fab")
		)
		(pad "1" smd rect
			(at 0 0 90)
			(size 0.508 0.508)
			(layers "F.Cu" "F.Mask" "F.Paste")
			(net "SMB_HOST_STBY_LVC3_SCL")
		)
		(pad "2" smd rect
			(at 0 0.889 90)
			(size 0.508 0.508)
			(layers "F.Cu" "F.Mask" "F.Paste")
			(net "SMB_HOST_STBY_LVC3_SCL_R4")
		)
		(zone
			(layer "F.Cu")
			(hatch none 0.5)
			(connect_pads
				(clearance 0)
			)
			(min_thickness 0.25)
			(keepout
				(tracks allowed)
				(vias not_allowed)
				(pads allowed)
				(copperpour not_allowed)
				(footprints allowed)
			)
			(placement
				(enabled no)
				(sheetname "")
			)
			(fill
				(thermal_gap 0.5)
				(thermal_bridge_width 0.5)
				(island_removal_mode 0)
			)
			(polygon
				(pts
					(xy 472.567 -30.353) (xy 472.567 -30.861) (xy 472.948 -30.861) (xy 472.948 -30.353)
				)
			)
		)
		(zone
			(layer "F.Cu")
			(hatch none 0.5)
			(connect_pads
				(clearance 0)
			)
			(min_thickness 0.25)
			(keepout
				(tracks not_allowed)
				(vias allowed)
				(pads allowed)
				(copperpour not_allowed)
				(footprints allowed)
			)
			(placement
				(enabled no)
				(sheetname "")
			)
			(fill
				(thermal_gap 0.5)
				(thermal_bridge_width 0.5)
				(island_removal_mode 0)
			)
			(polygon
				(pts
					(xy 472.948 -30.353) (xy 472.948 -30.861) (xy 472.567 -30.861) (xy 472.567 -30.353)
				)
			)
		)
	)
	(footprint ""
		(layer "F.Cu")
		(at 408.319478 -119.051832 90)
		(property "Reference" "R1W14"
			(at -0.8382 -0.67818 90)
			(unlocked yes)
			(layer "F.SilkS")
			(effects
				(font
					(size 0.4064 0.254)
					(thickness 0.1524)
				)
				(justify left)
			)
		)
		(property "Value" ""
			(at 0 0 90)
			(layer "F.Fab")
			(effects
				(font
					(size 1.27 1.27)
				)
			)
		)
		(duplicate_pad_numbers_are_jumpers no)
		(fp_poly
			(pts
				(xy -0.2794 -0.1016) (xy 0.2794 -0.1016) (xy 0.2794 0.9906) (xy -0.2794 0.9906)
			)
			(stroke
				(width 0)
				(type default)
			)
			(fill no)
			(layer "F.CrtYd")
		)
		(fp_line
			(start 0.2794 -0.1016)
			(end -0.2794 -0.1016)
			(stroke
				(width 0.1)
				(type default)
			)
			(layer "F.Fab")
		)
		(fp_line
			(start -0.2794 -0.1016)
			(end -0.2794 0.9906)
			(stroke
				(width 0.1)
				(type default)
			)
			(layer "F.Fab")
		)
		(fp_line
			(start 0.2794 0.9906)
			(end 0.2794 -0.1016)
			(stroke
				(width 0.1)
				(type default)
			)
			(layer "F.Fab")
		)
		(fp_line
			(start -0.2794 0.9906)
			(end 0.2794 0.9906)
			(stroke
				(width 0.1)
				(type default)
			)
			(layer "F.Fab")
		)
		(pad "1" smd rect
			(at 0 0 90)
			(size 0.508 0.508)
			(layers "F.Cu" "F.Mask" "F.Paste")
			(net "USB2_PCH_BMC_P5_DP_R")
		)
		(pad "2" smd rect
			(at 0 0.889 90)
			(size 0.508 0.508)
			(layers "F.Cu" "F.Mask" "F.Paste")
			(net "USB2_PCH_BMC_P5_DP")
		)
		(zone
			(layer "F.Cu")
			(hatch none 0.5)
			(connect_pads
				(clearance 0)
			)
			(min_thickness 0.25)
			(keepout
				(tracks allowed)
				(vias not_allowed)
				(pads allowed)
				(copperpour not_allowed)
				(footprints allowed)
			)
			(placement
				(enabled no)
				(sheetname "")
			)
			(fill
				(thermal_gap 0.5)
				(thermal_bridge_width 0.5)
				(island_removal_mode 0)
			)
			(polygon
				(pts
					(xy 408.573478 -118.797832) (xy 408.573478 -119.305832) (xy 408.954478 -119.305832) (xy 408.954478 -118.797832)
				)
			)
		)
		(zone
			(layer "F.Cu")
			(hatch none 0.5)
			(connect_pads
				(clearance 0)
			)
			(min_thickness 0.25)
			(keepout
				(tracks not_allowed)
				(vias allowed)
				(pads allowed)
				(copperpour not_allowed)
				(footprints allowed)
			)
			(placement
				(enabled no)
				(sheetname "")
			)
			(fill
				(thermal_gap 0.5)
				(thermal_bridge_width 0.5)
				(island_removal_mode 0)
			)
			(polygon
				(pts
					(xy 408.954478 -118.797832) (xy 408.954478 -119.305832) (xy 408.573478 -119.305832) (xy 408.573478 -118.797832)
				)
			)
		)
	)
)
